(kicad_pcb
	(version 20260206)
	(generator "pcbnew")
	(generator_version "10.0")
	(general
		(thickness 1.6)
		(legacy_teardrops no)
	)
	(paper "A4")
	(title_block
		(title "Wiwynn_Tioga_Pass_MB.brd")
		(comment 1 "Tioga Pass / footprint 4543 of 4770 (J9U2), pads 124-243 of 291")
	)
	(layers
		(0 "F.Cu" signal "TOP")
		(4 "In1.Cu" signal "L2GND")
		(6 "In2.Cu" signal "L3")
		(8 "In3.Cu" signal "L4GND")
		(10 "In4.Cu" signal "L5")
		(12 "In5.Cu" signal "L6GND")
		(14 "In6.Cu" signal "L7VCC")
		(16 "In7.Cu" signal "L8VCC")
		(18 "In8.Cu" signal "L9GND")
		(20 "In9.Cu" signal "L10")
		(22 "In10.Cu" signal "L11GND")
		(24 "In11.Cu" signal "L12")
		(26 "In12.Cu" signal "L13GND")
		(2 "B.Cu" signal "BOTTOM")
		(9 "F.Adhes" user "F.Adhesive")
		(11 "B.Adhes" user "B.Adhesive")
		(13 "F.Paste" user "Package Geometry/Pastemask Top")
		(15 "B.Paste" user "Package Geometry/Pastemask Bottom")
		(5 "F.SilkS" user "Ref Des/Silkscreen Top")
		(7 "B.SilkS" user "Ref Des/Silkscreen Bottom")
		(1 "F.Mask" user "Board Geometry/Soldermask Top")
		(3 "B.Mask" user "Board Geometry/Soldermask Bottom")
		(17 "Dwgs.User" user "User.Drawings")
		(19 "Cmts.User" user "User.Comments")
		(21 "Eco1.User" user "User.Eco1")
		(23 "Eco2.User" user "User.Eco2")
		(25 "Edge.Cuts" user "Board Geometry/Outline")
		(27 "Margin" user)
		(31 "F.CrtYd" user "Package Geometry/Place Bound Top")
		(29 "B.CrtYd" user "Package Geometry/Place Bound Bottom")
		(35 "F.Fab" user "Ref Des/Assembly Top")
		(33 "B.Fab" user "Ref Des/Assembly Bottom")
	)
	(footprint ""
		(layer "B.Cu")
		(at 29.699458 -5.621782 90)
		(property "Reference" "J9U2"
			(at 2.098548 38.118542 0)
			(unlocked yes)
			(layer "B.SilkS")
			(effects
				(font
					(size 0.7874 0.5842)
					(thickness 0.1524)
				)
				(justify left mirror)
			)
		)
		(property "Value" ""
			(at 0 0 90)
			(layer "B.Fab")
			(effects
				(font
					(size 1.27 1.27)
				)
				(justify mirror)
			)
		)
		(duplicate_pad_numbers_are_jumpers no)
		(pad "121" smd rect
			(at 0 107.100116 270)
			(size 1.8034 0.508)
			(layers "B.Cu" "B.Mask" "B.Paste")
			(net "M_J_DQS_DP<15>")
		)
		(pad "122" smd rect
			(at 0 107.95 270)
			(size 1.8034 0.508)
			(layers "B.Cu" "B.Mask" "B.Paste")
			(net "M_J_DQS_DN<15>")
		)
		(pad "123" smd rect
			(at 0 108.799884 270)
			(size 1.8034 0.508)
			(layers "B.Cu" "B.Mask" "B.Paste")
			(net "GND")
		)
		(pad "124" smd rect
			(at 0 109.650022 270)
			(size 1.8034 0.508)
			(layers "B.Cu" "B.Mask" "B.Paste")
			(net "M_J_DQ<54>")
		)
		(pad "125" smd rect
			(at 0 110.499906 270)
			(size 1.8034 0.508)
			(layers "B.Cu" "B.Mask" "B.Paste")
			(net "GND")
		)
		(pad "126" smd rect
			(at 0 111.350044 270)
			(size 1.8034 0.508)
			(layers "B.Cu" "B.Mask" "B.Paste")
			(net "M_J_DQ<50>")
		)
		(pad "127" smd rect
			(at 0 112.199928 270)
			(size 1.8034 0.508)
			(layers "B.Cu" "B.Mask" "B.Paste")
			(net "GND")
		)
		(pad "128" smd rect
			(at 0 113.050066 270)
			(size 1.8034 0.508)
			(layers "B.Cu" "B.Mask" "B.Paste")
			(net "M_J_DQ<60>")
		)
		(pad "129" smd rect
			(at 0 113.89995 270)
			(size 1.8034 0.508)
			(layers "B.Cu" "B.Mask" "B.Paste")
			(net "GND")
		)
		(pad "130" smd rect
			(at 0 114.750088 270)
			(size 1.8034 0.508)
			(layers "B.Cu" "B.Mask" "B.Paste")
			(net "M_J_DQ<56>")
		)
		(pad "131" smd rect
			(at 0 115.599972 270)
			(size 1.8034 0.508)
			(layers "B.Cu" "B.Mask" "B.Paste")
			(net "GND")
		)
		(pad "132" smd rect
			(at 0 116.45011 270)
			(size 1.8034 0.508)
			(layers "B.Cu" "B.Mask" "B.Paste")
			(net "M_J_DQS_DP<16>")
		)
		(pad "133" smd rect
			(at 0 117.299994 270)
			(size 1.8034 0.508)
			(layers "B.Cu" "B.Mask" "B.Paste")
			(net "M_J_DQS_DN<16>")
		)
		(pad "134" smd rect
			(at 0 118.149878 270)
			(size 1.8034 0.508)
			(layers "B.Cu" "B.Mask" "B.Paste")
			(net "GND")
		)
		(pad "135" smd rect
			(at 0 119.000016 270)
			(size 1.8034 0.508)
			(layers "B.Cu" "B.Mask" "B.Paste")
			(net "M_J_DQ<62>")
		)
		(pad "136" smd rect
			(at 0 119.8499 270)
			(size 1.8034 0.508)
			(layers "B.Cu" "B.Mask" "B.Paste")
			(net "GND")
		)
		(pad "137" smd rect
			(at 0 120.700038 270)
			(size 1.8034 0.508)
			(layers "B.Cu" "B.Mask" "B.Paste")
			(net "M_J_DQ<58>")
		)
		(pad "138" smd rect
			(at 0 121.549922 270)
			(size 1.8034 0.508)
			(layers "B.Cu" "B.Mask" "B.Paste")
			(net "GND")
		)
		(pad "139" smd rect
			(at 0 122.40006 270)
			(size 1.8034 0.508)
			(layers "B.Cu" "B.Mask" "B.Paste")
			(net "PVPP_GHJ")
		)
		(pad "140" smd rect
			(at 0 123.249944 270)
			(size 1.8034 0.508)
			(layers "B.Cu" "B.Mask" "B.Paste")
			(net "GND")
		)
		(pad "141" smd rect
			(at 0 124.100082 270)
			(size 1.8034 0.508)
			(layers "B.Cu" "B.Mask" "B.Paste")
			(net "SMB_DDR_GHJ_VPP_SCL")
		)
		(pad "142" smd rect
			(at 0 124.949966 270)
			(size 1.8034 0.508)
			(layers "B.Cu" "B.Mask" "B.Paste")
			(net "PVPP_GHJ")
		)
		(pad "143" smd rect
			(at 0 125.800104 270)
			(size 1.8034 0.508)
			(layers "B.Cu" "B.Mask" "B.Paste")
			(net "PVPP_GHJ")
		)
		(pad "144" smd rect
			(at 0 126.649988 270)
			(size 1.8034 0.508)
			(layers "B.Cu" "B.Mask" "B.Paste")
			(net "TP_CH_J_DIMM_J1_RFU_2")
		)
		(pad "145" smd rect
			(at -4.59994 0 270)
			(size 1.8034 0.508)
			(layers "B.Cu" "B.Mask" "B.Paste")
			(net "P12V_NVDIMM_GHJ")
		)
		(pad "146" smd rect
			(at -4.59994 0.849884 270)
			(size 1.8034 0.508)
			(layers "B.Cu" "B.Mask" "B.Paste")
			(net "M_J_VREF")
		)
		(pad "147" smd rect
			(at -4.59994 1.700022 270)
			(size 1.8034 0.508)
			(layers "B.Cu" "B.Mask" "B.Paste")
			(net "GND")
		)
		(pad "148" smd rect
			(at -4.59994 2.549906 270)
			(size 1.8034 0.508)
			(layers "B.Cu" "B.Mask" "B.Paste")
			(net "M_J_DQ<5>")
		)
		(pad "149" smd rect
			(at -4.59994 3.400044 270)
			(size 1.8034 0.508)
			(layers "B.Cu" "B.Mask" "B.Paste")
			(net "GND")
		)
		(pad "150" smd rect
			(at -4.59994 4.249928 270)
			(size 1.8034 0.508)
			(layers "B.Cu" "B.Mask" "B.Paste")
			(net "M_J_DQ<1>")
		)
		(pad "151" smd rect
			(at -4.59994 5.100066 270)
			(size 1.8034 0.508)
			(layers "B.Cu" "B.Mask" "B.Paste")
			(net "GND")
		)
		(pad "152" smd rect
			(at -4.59994 5.94995 270)
			(size 1.8034 0.508)
			(layers "B.Cu" "B.Mask" "B.Paste")
			(net "M_J_DQS_DN<0>")
		)
		(pad "153" smd rect
			(at -4.59994 6.800088 270)
			(size 1.8034 0.508)
			(layers "B.Cu" "B.Mask" "B.Paste")
			(net "M_J_DQS_DP<0>")
		)
		(pad "154" smd rect
			(at -4.59994 7.649972 270)
			(size 1.8034 0.508)
			(layers "B.Cu" "B.Mask" "B.Paste")
			(net "GND")
		)
		(pad "155" smd rect
			(at -4.59994 8.50011 270)
			(size 1.8034 0.508)
			(layers "B.Cu" "B.Mask" "B.Paste")
			(net "M_J_DQ<7>")
		)
		(pad "156" smd rect
			(at -4.59994 9.349994 270)
			(size 1.8034 0.508)
			(layers "B.Cu" "B.Mask" "B.Paste")
			(net "GND")
		)
		(pad "157" smd rect
			(at -4.59994 10.199878 270)
			(size 1.8034 0.508)
			(layers "B.Cu" "B.Mask" "B.Paste")
			(net "M_J_DQ<3>")
		)
		(pad "158" smd rect
			(at -4.59994 11.050016 270)
			(size 1.8034 0.508)
			(layers "B.Cu" "B.Mask" "B.Paste")
			(net "GND")
		)
		(pad "159" smd rect
			(at -4.59994 11.8999 270)
			(size 1.8034 0.508)
			(layers "B.Cu" "B.Mask" "B.Paste")
			(net "M_J_DQ<13>")
		)
		(pad "160" smd rect
			(at -4.59994 12.750038 270)
			(size 1.8034 0.508)
			(layers "B.Cu" "B.Mask" "B.Paste")
			(net "GND")
		)
		(pad "161" smd rect
			(at -4.59994 13.599922 270)
			(size 1.8034 0.508)
			(layers "B.Cu" "B.Mask" "B.Paste")
			(net "M_J_DQ<9>")
		)
		(pad "162" smd rect
			(at -4.59994 14.45006 270)
			(size 1.8034 0.508)
			(layers "B.Cu" "B.Mask" "B.Paste")
			(net "GND")
		)
		(pad "163" smd rect
			(at -4.59994 15.299944 270)
			(size 1.8034 0.508)
			(layers "B.Cu" "B.Mask" "B.Paste")
			(net "M_J_DQS_DN<1>")
		)
		(pad "164" smd rect
			(at -4.59994 16.150082 270)
			(size 1.8034 0.508)
			(layers "B.Cu" "B.Mask" "B.Paste")
			(net "M_J_DQS_DP<1>")
		)
		(pad "165" smd rect
			(at -4.59994 16.999966 270)
			(size 1.8034 0.508)
			(layers "B.Cu" "B.Mask" "B.Paste")
			(net "GND")
		)
		(pad "166" smd rect
			(at -4.59994 17.850104 270)
			(size 1.8034 0.508)
			(layers "B.Cu" "B.Mask" "B.Paste")
			(net "M_J_DQ<15>")
		)
		(pad "167" smd rect
			(at -4.59994 18.699988 270)
			(size 1.8034 0.508)
			(layers "B.Cu" "B.Mask" "B.Paste")
			(net "GND")
		)
		(pad "168" smd rect
			(at -4.59994 19.550126 270)
			(size 1.8034 0.508)
			(layers "B.Cu" "B.Mask" "B.Paste")
			(net "M_J_DQ<11>")
		)
		(pad "169" smd rect
			(at -4.59994 20.40001 270)
			(size 1.8034 0.508)
			(layers "B.Cu" "B.Mask" "B.Paste")
			(net "GND")
		)
		(pad "170" smd rect
			(at -4.59994 21.249894 270)
			(size 1.8034 0.508)
			(layers "B.Cu" "B.Mask" "B.Paste")
			(net "M_J_DQ<21>")
		)
		(pad "171" smd rect
			(at -4.59994 22.100032 270)
			(size 1.8034 0.508)
			(layers "B.Cu" "B.Mask" "B.Paste")
			(net "GND")
		)
		(pad "172" smd rect
			(at -4.59994 22.949916 270)
			(size 1.8034 0.508)
			(layers "B.Cu" "B.Mask" "B.Paste")
			(net "M_J_DQ<17>")
		)
		(pad "173" smd rect
			(at -4.59994 23.800054 270)
			(size 1.8034 0.508)
			(layers "B.Cu" "B.Mask" "B.Paste")
			(net "GND")
		)
		(pad "174" smd rect
			(at -4.59994 24.649938 270)
			(size 1.8034 0.508)
			(layers "B.Cu" "B.Mask" "B.Paste")
			(net "M_J_DQS_DN<2>")
		)
		(pad "175" smd rect
			(at -4.59994 25.500076 270)
			(size 1.8034 0.508)
			(layers "B.Cu" "B.Mask" "B.Paste")
			(net "M_J_DQS_DP<2>")
		)
		(pad "176" smd rect
			(at -4.59994 26.34996 270)
			(size 1.8034 0.508)
			(layers "B.Cu" "B.Mask" "B.Paste")
			(net "GND")
		)
		(pad "177" smd rect
			(at -4.59994 27.200098 270)
			(size 1.8034 0.508)
			(layers "B.Cu" "B.Mask" "B.Paste")
			(net "M_J_DQ<23>")
		)
		(pad "178" smd rect
			(at -4.59994 28.049982 270)
			(size 1.8034 0.508)
			(layers "B.Cu" "B.Mask" "B.Paste")
			(net "GND")
		)
		(pad "179" smd rect
			(at -4.59994 28.90012 270)
			(size 1.8034 0.508)
			(layers "B.Cu" "B.Mask" "B.Paste")
			(net "M_J_DQ<19>")
		)
		(pad "180" smd rect
			(at -4.59994 29.750004 270)
			(size 1.8034 0.508)
			(layers "B.Cu" "B.Mask" "B.Paste")
			(net "GND")
		)
		(pad "181" smd rect
			(at -4.59994 30.599888 270)
			(size 1.8034 0.508)
			(layers "B.Cu" "B.Mask" "B.Paste")
			(net "M_J_DQ<29>")
		)
		(pad "182" smd rect
			(at -4.59994 31.450026 270)
			(size 1.8034 0.508)
			(layers "B.Cu" "B.Mask" "B.Paste")
			(net "GND")
		)
		(pad "183" smd rect
			(at -4.59994 32.29991 270)
			(size 1.8034 0.508)
			(layers "B.Cu" "B.Mask" "B.Paste")
			(net "M_J_DQ<25>")
		)
		(pad "184" smd rect
			(at -4.59994 33.150048 270)
			(size 1.8034 0.508)
			(layers "B.Cu" "B.Mask" "B.Paste")
			(net "GND")
		)
		(pad "185" smd rect
			(at -4.59994 33.999932 270)
			(size 1.8034 0.508)
			(layers "B.Cu" "B.Mask" "B.Paste")
			(net "M_J_DQS_DN<3>")
		)
		(pad "186" smd rect
			(at -4.59994 34.85007 270)
			(size 1.8034 0.508)
			(layers "B.Cu" "B.Mask" "B.Paste")
			(net "M_J_DQS_DP<3>")
		)
		(pad "187" smd rect
			(at -4.59994 35.699954 270)
			(size 1.8034 0.508)
			(layers "B.Cu" "B.Mask" "B.Paste")
			(net "GND")
		)
		(pad "188" smd rect
			(at -4.59994 36.550092 270)
			(size 1.8034 0.508)
			(layers "B.Cu" "B.Mask" "B.Paste")
			(net "M_J_DQ<31>")
		)
		(pad "189" smd rect
			(at -4.59994 37.399976 270)
			(size 1.8034 0.508)
			(layers "B.Cu" "B.Mask" "B.Paste")
			(net "GND")
		)
		(pad "190" smd rect
			(at -4.59994 38.250114 270)
			(size 1.8034 0.508)
			(layers "B.Cu" "B.Mask" "B.Paste")
			(net "M_J_DQ<27>")
		)
		(pad "191" smd rect
			(at -4.59994 39.099998 270)
			(size 1.8034 0.508)
			(layers "B.Cu" "B.Mask" "B.Paste")
			(net "GND")
		)
		(pad "192" smd rect
			(at -4.59994 39.949882 270)
			(size 1.8034 0.508)
			(layers "B.Cu" "B.Mask" "B.Paste")
			(net "M_J_ECC<5>")
		)
		(pad "193" smd rect
			(at -4.59994 40.80002 270)
			(size 1.8034 0.508)
			(layers "B.Cu" "B.Mask" "B.Paste")
			(net "GND")
		)
		(pad "194" smd rect
			(at -4.59994 41.649904 270)
			(size 1.8034 0.508)
			(layers "B.Cu" "B.Mask" "B.Paste")
			(net "M_J_ECC<1>")
		)
		(pad "195" smd rect
			(at -4.59994 42.500042 270)
			(size 1.8034 0.508)
			(layers "B.Cu" "B.Mask" "B.Paste")
			(net "GND")
		)
		(pad "196" smd rect
			(at -4.59994 43.349926 270)
			(size 1.8034 0.508)
			(layers "B.Cu" "B.Mask" "B.Paste")
			(net "M_J_DQS_DN<8>")
		)
		(pad "197" smd rect
			(at -4.59994 44.200064 270)
			(size 1.8034 0.508)
			(layers "B.Cu" "B.Mask" "B.Paste")
			(net "M_J_DQS_DP<8>")
		)
		(pad "198" smd rect
			(at -4.59994 45.049948 270)
			(size 1.8034 0.508)
			(layers "B.Cu" "B.Mask" "B.Paste")
			(net "GND")
		)
		(pad "199" smd rect
			(at -4.59994 45.900086 270)
			(size 1.8034 0.508)
			(layers "B.Cu" "B.Mask" "B.Paste")
			(net "M_J_ECC<7>")
		)
		(pad "200" smd rect
			(at -4.59994 46.74997 270)
			(size 1.8034 0.508)
			(layers "B.Cu" "B.Mask" "B.Paste")
			(net "GND")
		)
		(pad "201" smd rect
			(at -4.59994 47.600108 270)
			(size 1.8034 0.508)
			(layers "B.Cu" "B.Mask" "B.Paste")
			(net "M_J_ECC<3>")
		)
		(pad "202" smd rect
			(at -4.59994 48.449992 270)
			(size 1.8034 0.508)
			(layers "B.Cu" "B.Mask" "B.Paste")
			(net "GND")
		)
		(pad "203" smd rect
			(at -4.59994 49.299876 270)
			(size 1.8034 0.508)
			(layers "B.Cu" "B.Mask" "B.Paste")
			(net "M_J_CKE<3>")
		)
		(pad "204" smd rect
			(at -4.59994 50.150014 270)
			(size 1.8034 0.508)
			(layers "B.Cu" "B.Mask" "B.Paste")
			(net "PVDDQ_GHJ")
		)
		(pad "205" smd rect
			(at -4.59994 50.999898 270)
			(size 1.8034 0.508)
			(layers "B.Cu" "B.Mask" "B.Paste")
			(net "TP_CH_J_DIMM_J1_RFU_0")
		)
		(pad "206" smd rect
			(at -4.59994 51.850036 270)
			(size 1.8034 0.508)
			(layers "B.Cu" "B.Mask" "B.Paste")
			(net "PVDDQ_GHJ")
		)
		(pad "207" smd rect
			(at -4.59994 52.69992 270)
			(size 1.8034 0.508)
			(layers "B.Cu" "B.Mask" "B.Paste")
			(net "M_J_BG<1>")
		)
		(pad "208" smd rect
			(at -4.59994 53.550058 270)
			(size 1.8034 0.508)
			(layers "B.Cu" "B.Mask" "B.Paste")
			(net "M_J_ALERT_N")
		)
		(pad "209" smd rect
			(at -4.59994 54.399942 270)
			(size 1.8034 0.508)
			(layers "B.Cu" "B.Mask" "B.Paste")
			(net "PVDDQ_GHJ")
		)
		(pad "210" smd rect
			(at -4.59994 55.25008 270)
			(size 1.8034 0.508)
			(layers "B.Cu" "B.Mask" "B.Paste")
			(net "M_J_MA<11>")
		)
		(pad "211" smd rect
			(at -4.59994 56.099964 270)
			(size 1.8034 0.508)
			(layers "B.Cu" "B.Mask" "B.Paste")
			(net "M_J_MA<7>")
		)
		(pad "212" smd rect
			(at -4.59994 56.950102 270)
			(size 1.8034 0.508)
			(layers "B.Cu" "B.Mask" "B.Paste")
			(net "PVDDQ_GHJ")
		)
		(pad "213" smd rect
			(at -4.59994 57.799986 270)
			(size 1.8034 0.508)
			(layers "B.Cu" "B.Mask" "B.Paste")
			(net "M_J_MA<5>")
		)
		(pad "214" smd rect
			(at -4.59994 58.650124 270)
			(size 1.8034 0.508)
			(layers "B.Cu" "B.Mask" "B.Paste")
			(net "M_J_MA<4>")
		)
		(pad "215" smd rect
			(at -4.59994 59.500008 270)
			(size 1.8034 0.508)
			(layers "B.Cu" "B.Mask" "B.Paste")
			(net "PVDDQ_GHJ")
		)
		(pad "216" smd rect
			(at -4.59994 60.349892 270)
			(size 1.8034 0.508)
			(layers "B.Cu" "B.Mask" "B.Paste")
			(net "M_J_MA<2>")
		)
		(pad "217" smd rect
			(at -4.59994 61.20003 270)
			(size 1.8034 0.508)
			(layers "B.Cu" "B.Mask" "B.Paste")
			(net "PVDDQ_GHJ")
		)
		(pad "218" smd rect
			(at -4.59994 62.049914 270)
			(size 1.8034 0.508)
			(layers "B.Cu" "B.Mask" "B.Paste")
			(net "M_J_CLK_DP<3>")
		)
		(pad "219" smd rect
			(at -4.59994 62.900052 270)
			(size 1.8034 0.508)
			(layers "B.Cu" "B.Mask" "B.Paste")
			(net "M_J_CLK_DN<3>")
		)
		(pad "220" smd rect
			(at -4.59994 63.749936 270)
			(size 1.8034 0.508)
			(layers "B.Cu" "B.Mask" "B.Paste")
			(net "PVDDQ_GHJ")
		)
		(pad "221" smd rect
			(at -4.59994 64.600074 270)
			(size 1.8034 0.508)
			(layers "B.Cu" "B.Mask" "B.Paste")
			(net "PVTT_GHJ")
		)
		(pad "222" smd rect
			(at -4.59994 70.550024 270)
			(size 1.8034 0.508)
			(layers "B.Cu" "B.Mask" "B.Paste")
			(net "M_J_PAR")
		)
		(pad "223" smd rect
			(at -4.59994 71.399908 270)
			(size 1.8034 0.508)
			(layers "B.Cu" "B.Mask" "B.Paste")
			(net "PVDDQ_GHJ")
		)
		(pad "224" smd rect
			(at -4.59994 72.250046 270)
			(size 1.8034 0.508)
			(layers "B.Cu" "B.Mask" "B.Paste")
			(net "M_J_BA<1>")
		)
		(pad "225" smd rect
			(at -4.59994 73.09993 270)
			(size 1.8034 0.508)
			(layers "B.Cu" "B.Mask" "B.Paste")
			(net "M_J_MA<10>")
		)
		(pad "226" smd rect
			(at -4.59994 73.950068 270)
			(size 1.8034 0.508)
			(layers "B.Cu" "B.Mask" "B.Paste")
			(net "PVDDQ_GHJ")
		)
		(pad "227" smd rect
			(at -4.59994 74.799952 270)
			(size 1.8034 0.508)
			(layers "B.Cu" "B.Mask" "B.Paste")
			(net "TP_CH_J_DIMM_J1_RFU_1")
		)
		(pad "228" smd rect
			(at -4.59994 75.65009 270)
			(size 1.8034 0.508)
			(layers "B.Cu" "B.Mask" "B.Paste")
			(net "M_J_MA<14>")
		)
		(pad "229" smd rect
			(at -4.59994 76.499974 270)
			(size 1.8034 0.508)
			(layers "B.Cu" "B.Mask" "B.Paste")
			(net "PVDDQ_GHJ")
		)
		(pad "230" smd rect
			(at -4.59994 77.350112 270)
			(size 1.8034 0.508)
			(layers "B.Cu" "B.Mask" "B.Paste")
			(net "FM_ADR_COMPLETE_GHJ_N")
		)
		(pad "231" smd rect
			(at -4.59994 78.199996 270)
			(size 1.8034 0.508)
			(layers "B.Cu" "B.Mask" "B.Paste")
			(net "PVDDQ_GHJ")
		)
		(pad "232" smd rect
			(at -4.59994 79.04988 270)
			(size 1.8034 0.508)
			(layers "B.Cu" "B.Mask" "B.Paste")
			(net "M_J_MA<13>")
		)
		(pad "233" smd rect
			(at -4.59994 79.900018 270)
			(size 1.8034 0.508)
			(layers "B.Cu" "B.Mask" "B.Paste")
			(net "PVDDQ_GHJ")
		)
		(pad "234" smd rect
			(at -4.59994 80.749902 270)
			(size 1.8034 0.508)
			(layers "B.Cu" "B.Mask" "B.Paste")
			(net "M_J_MA<17>")
		)
		(pad "235" smd rect
			(at -4.59994 81.60004 270)
			(size 1.8034 0.508)
			(layers "B.Cu" "B.Mask" "B.Paste")
			(net "M_J_C<2>")
		)
		(pad "236" smd rect
			(at -4.59994 82.449924 270)
			(size 1.8034 0.508)
			(layers "B.Cu" "B.Mask" "B.Paste")
			(net "PVDDQ_GHJ")
		)
		(pad "237" smd rect
			(at -4.59994 83.300062 270)
			(size 1.8034 0.508)
			(layers "B.Cu" "B.Mask" "B.Paste")
			(net "M_J_CS_N<7>")
		)
		(pad "238" smd rect
			(at -4.59994 84.149946 270)
			(size 1.8034 0.508)
			(layers "B.Cu" "B.Mask" "B.Paste")
			(net "PVPP_GHJ")
		)
		(pad "239" smd rect
			(at -4.59994 85.000084 270)
			(size 1.8034 0.508)
			(layers "B.Cu" "B.Mask" "B.Paste")
			(net "GND")
		)
		(pad "240" smd rect
			(at -4.59994 85.849968 270)
			(size 1.8034 0.508)
			(layers "B.Cu" "B.Mask" "B.Paste")
			(net "M_J_DQ<37>")
		)
	)
)
